(kicad_pcb
	(version 20260206)
	(generator "pcbnew")
	(generator_version "10.0")
	(general
		(thickness 1.6)
		(legacy_teardrops no)
	)
	(paper "A4")
	(title_block
		(title "peb — Lightning_PEB_BRD.brd")
		(comment 1 "Lightning (Wiwynn / Facebook NVMe JBOF) / footprints 2100-2107 of 2563")
	)
	(layers
		(0 "F.Cu" signal "TOP")
		(4 "In1.Cu" signal "L2GND")
		(6 "In2.Cu" signal "L3")
		(8 "In3.Cu" signal "L4VCC")
		(10 "In4.Cu" signal "L5VCC")
		(12 "In5.Cu" signal "L6")
		(14 "In6.Cu" signal "L7GND")
		(2 "B.Cu" signal "BOTTOM")
		(9 "F.Adhes" user "F.Adhesive")
		(11 "B.Adhes" user "B.Adhesive")
		(13 "F.Paste" user "Package Geometry/Pastemask Top")
		(15 "B.Paste" user "Package Geometry/Pastemask Bottom")
		(5 "F.SilkS" user "Ref Des/Silkscreen Top")
		(7 "B.SilkS" user "Ref Des/Silkscreen Bottom")
		(1 "F.Mask" user "Board Geometry/Soldermask Top")
		(3 "B.Mask" user "Board Geometry/Soldermask Bottom")
		(17 "Dwgs.User" user "User.Drawings")
		(19 "Cmts.User" user "User.Comments")
		(21 "Eco1.User" user "User.Eco1")
		(23 "Eco2.User" user "User.Eco2")
		(25 "Edge.Cuts" user "Board Geometry/Outline")
		(27 "Margin" user)
		(31 "F.CrtYd" user "Package Geometry/Place Bound Top")
		(29 "B.CrtYd" user "Package Geometry/Place Bound Bottom")
		(35 "F.Fab" user "Ref Des/Assembly Top")
		(33 "B.Fab" user "Ref Des/Assembly Bottom")
	)
	(footprint ""
		(layer "B.Cu")
		(at 224.040446 -203.69784 180)
		(property "Reference" "R4144"
			(at 0 0 0)
			(layer "B.SilkS")
			(hide yes)
			(effects
				(font
					(size 1.27 1.27)
				)
				(justify mirror)
			)
		)
		(property "Value" "4K7R2F-GP"
			(at -0.064008 -3.993896 180)
			(unlocked yes)
			(layer "B.Fab")
			(hide yes)
			(effects
				(font
					(size 1.016 1.016)
					(thickness 0.1524)
				)
				(justify mirror)
			)
		)
		(property "Device Type" "R402H16"
			(at -0.064008 -5.517896 180)
			(unlocked yes)
			(layer "B.Fab")
			(hide yes)
			(effects
				(font
					(size 1.016 1.016)
					(thickness 0.1524)
				)
				(justify mirror)
			)
		)
		(duplicate_pad_numbers_are_jumpers no)
		(fp_line
			(start 0.508 -0.9398)
			(end 0.508 0.9398)
			(stroke
				(width 0.1524)
				(type default)
			)
			(layer "B.SilkS")
		)
		(fp_line
			(start -0.508 -0.9398)
			(end 0.508 -0.9398)
			(stroke
				(width 0.1524)
				(type default)
			)
			(layer "B.SilkS")
		)
		(fp_rect
			(start 0.508 0.9398)
			(end -0.508 -0.9398)
			(stroke
				(width 0)
				(type default)
			)
			(fill no)
			(layer "B.CrtYd")
		)
		(fp_rect
			(start 0.508 0.9398)
			(end -0.508 -0.9398)
			(stroke
				(width 0)
				(type default)
			)
			(fill no)
			(layer "B.Fab")
		)
		(pad "1" smd custom
			(at 0 -0.4445)
			(size 0.1397 0.1397)
			(layers "B.Cu" "B.Mask" "B.Paste")
			(net "SSD_PRSNT#13")
			(options
				(clearance outline)
				(anchor circle)
			)
			(primitives
				(gr_poly
					(pts
						(arc
							(start -0.1778 0.2794)
							(mid -0.249642 0.249642)
							(end -0.2794 0.1778)
						)
						(arc
							(start -0.2794 -0.1778)
							(mid -0.249642 -0.249642)
							(end -0.1778 -0.2794)
						)
						(arc
							(start 0.1778 -0.2794)
							(mid 0.249642 -0.249642)
							(end 0.2794 -0.1778)
						)
						(arc
							(start 0.2794 0.1778)
							(mid 0.249642 0.249642)
							(end 0.1778 0.2794)
						)
					)
					(width 0)
					(fill yes)
				)
			)
		)
		(pad "2" smd custom
			(at 0 0.4445)
			(size 0.1397 0.1397)
			(layers "B.Cu" "B.Mask" "B.Paste")
			(net "P3V3_STBY")
			(options
				(clearance outline)
				(anchor circle)
			)
			(primitives
				(gr_poly
					(pts
						(arc
							(start -0.1778 0.2794)
							(mid -0.249642 0.249642)
							(end -0.2794 0.1778)
						)
						(arc
							(start -0.2794 -0.1778)
							(mid -0.249642 -0.249642)
							(end -0.1778 -0.2794)
						)
						(arc
							(start 0.1778 -0.2794)
							(mid 0.249642 -0.249642)
							(end 0.2794 -0.1778)
						)
						(arc
							(start 0.2794 0.1778)
							(mid 0.249642 0.249642)
							(end 0.1778 0.2794)
						)
					)
					(width 0)
					(fill yes)
				)
			)
		)
	)
	(footprint ""
		(layer "B.Cu")
		(at 230.6066 -31.9786)
		(property "Reference" "C479"
			(at 0 0 0)
			(layer "B.SilkS")
			(hide yes)
			(effects
				(font
					(size 1.27 1.27)
				)
				(justify mirror)
			)
		)
		(property "Value" "SCD1U16V1KX-1-GP"
			(at 2.8321 -1.7399 0)
			(unlocked yes)
			(layer "B.Fab")
			(hide yes)
			(effects
				(font
					(size 1.016 1.016)
					(thickness 0.1524)
				)
				(justify mirror)
			)
		)
		(property "Device Type" "C0201H13"
			(at 2.8321 -3.2639 0)
			(unlocked yes)
			(layer "B.Fab")
			(hide yes)
			(effects
				(font
					(size 1.016 1.016)
					(thickness 0.1524)
				)
				(justify mirror)
			)
		)
		(duplicate_pad_numbers_are_jumpers no)
		(fp_rect
			(start 0.2794 0.6477)
			(end -0.2794 -0.6477)
			(stroke
				(width 0)
				(type default)
			)
			(fill no)
			(layer "B.CrtYd")
		)
		(fp_rect
			(start 0.2794 0.6477)
			(end -0.2794 -0.6477)
			(stroke
				(width 0)
				(type default)
			)
			(fill no)
			(layer "B.Fab")
		)
		(pad "1" smd custom
			(at 0 -0.2794 180)
			(size 0.0762 0.0762)
			(layers "B.Cu" "B.Mask" "B.Paste")
			(net "DUT_VDDO")
			(options
				(clearance outline)
				(anchor circle)
			)
			(primitives
				(gr_poly
					(pts
						(arc
							(start 0.1524 0.127)
							(mid 0.137521 0.162921)
							(end 0.1016 0.1778)
						)
						(arc
							(start -0.1016 0.1778)
							(mid -0.137521 0.162921)
							(end -0.1524 0.127)
						)
						(arc
							(start -0.1524 -0.127)
							(mid -0.137521 -0.162921)
							(end -0.1016 -0.1778)
						)
						(arc
							(start 0.1016 -0.1778)
							(mid 0.137521 -0.162921)
							(end 0.1524 -0.127)
						)
					)
					(width 0)
					(fill yes)
				)
			)
		)
		(pad "2" smd custom
			(at 0 0.2794 180)
			(size 0.0762 0.0762)
			(layers "B.Cu" "B.Mask" "B.Paste")
			(net "GND")
			(options
				(clearance outline)
				(anchor circle)
			)
			(primitives
				(gr_poly
					(pts
						(arc
							(start 0.1524 0.127)
							(mid 0.137521 0.162921)
							(end 0.1016 0.1778)
						)
						(arc
							(start -0.1016 0.1778)
							(mid -0.137521 0.162921)
							(end -0.1524 0.127)
						)
						(arc
							(start -0.1524 -0.127)
							(mid -0.137521 -0.162921)
							(end -0.1016 -0.1778)
						)
						(arc
							(start 0.1016 -0.1778)
							(mid 0.137521 -0.162921)
							(end 0.1524 -0.127)
						)
					)
					(width 0)
					(fill yes)
				)
			)
		)
	)
	(footprint ""
		(layer "B.Cu")
		(at 341.432388 -178.808126)
		(property "Reference" "U78"
			(at 0 0 0)
			(layer "B.SilkS")
			(hide yes)
			(effects
				(font
					(size 1.27 1.27)
				)
				(justify mirror)
			)
		)
		(property "Value" "SN74LVC1G08DCKR-GP"
			(at 2.3368 -8.6868 0)
			(unlocked yes)
			(layer "B.Fab")
			(hide yes)
			(effects
				(font
					(size 1.016 1.016)
					(thickness 0.1524)
				)
				(justify mirror)
			)
		)
		(property "Device Type" "SC70-5H44"
			(at 2.3114 -10.414 0)
			(unlocked yes)
			(layer "B.Fab")
			(hide yes)
			(effects
				(font
					(size 1.016 1.016)
					(thickness 0.1524)
				)
				(justify mirror)
			)
		)
		(duplicate_pad_numbers_are_jumpers no)
		(fp_line
			(start -1.3843 -1.8034)
			(end -1.3843 -1.1176)
			(stroke
				(width 0.3302)
				(type default)
			)
			(layer "B.SilkS")
		)
		(fp_line
			(start -1.27 -1.7018)
			(end -1.27 1.7018)
			(stroke
				(width 0.1524)
				(type default)
			)
			(layer "B.SilkS")
		)
		(fp_line
			(start -1.27 1.7018)
			(end 1.27 1.7018)
			(stroke
				(width 0.1524)
				(type default)
			)
			(layer "B.SilkS")
		)
		(fp_line
			(start -0.6604 -1.8034)
			(end -1.3843 -1.8034)
			(stroke
				(width 0.3302)
				(type default)
			)
			(layer "B.SilkS")
		)
		(fp_line
			(start 1.27 -1.7018)
			(end -1.27 -1.7018)
			(stroke
				(width 0.1524)
				(type default)
			)
			(layer "B.SilkS")
		)
		(fp_line
			(start 1.27 1.7018)
			(end 1.27 -1.7018)
			(stroke
				(width 0.1524)
				(type default)
			)
			(layer "B.SilkS")
		)
		(fp_rect
			(start 1.524 1.9558)
			(end -1.524 -1.9558)
			(stroke
				(width 0)
				(type default)
			)
			(fill no)
			(layer "B.CrtYd")
		)
		(fp_poly
			(pts
				(xy 1.524 -1.9558) (xy -1.524 -1.9558) (xy -1.524 1.9558) (xy 1.524 1.9558)
			)
			(stroke
				(width 0)
				(type default)
			)
			(fill no)
			(layer "B.Fab")
		)
		(pad "1" smd rect
			(at -0.65024 -0.8255 180)
			(size 0.4064 1.2192)
			(layers "B.Cu" "B.Mask" "B.Paste")
			(net "BMC_SSD_RST#0_A14")
		)
		(pad "2" smd rect
			(at 0 -0.8255 180)
			(size 0.4064 1.2192)
			(layers "B.Cu" "B.Mask" "B.Paste")
			(net "SSD_PERST#0_B14")
		)
		(pad "3" smd rect
			(at 0.65024 -0.8255 180)
			(size 0.4064 1.2192)
			(layers "B.Cu" "B.Mask" "B.Paste")
			(net "GND")
		)
		(pad "4" smd rect
			(at 0.65024 0.8255 180)
			(size 0.4064 1.2192)
			(layers "B.Cu" "B.Mask" "B.Paste")
			(net "SSD_PERST_Y14")
		)
		(pad "5" smd rect
			(at -0.65024 0.8255 180)
			(size 0.4064 1.2192)
			(layers "B.Cu" "B.Mask" "B.Paste")
			(net "P3V3_STBY")
		)
	)
	(footprint ""
		(layer "B.Cu")
		(at 306.76723 -34.71926)
		(property "Reference" "C230"
			(at 0 0 0)
			(layer "B.SilkS")
			(hide yes)
			(effects
				(font
					(size 1.27 1.27)
				)
				(justify mirror)
			)
		)
		(property "Value" "SCD1U10V2KX-5GP"
			(at -1.1811 -2.7051 0)
			(unlocked yes)
			(layer "B.Fab")
			(hide yes)
			(effects
				(font
					(size 1.016 1.016)
					(thickness 0.1524)
				)
				(justify mirror)
			)
		)
		(property "Device Type" "C402H22"
			(at -1.1811 -4.2291 0)
			(unlocked yes)
			(layer "B.Fab")
			(hide yes)
			(effects
				(font
					(size 1.016 1.016)
					(thickness 0.1524)
				)
				(justify mirror)
			)
		)
		(duplicate_pad_numbers_are_jumpers no)
		(fp_rect
			(start 0.4318 0.9525)
			(end -0.4318 -0.9525)
			(stroke
				(width 0)
				(type default)
			)
			(fill no)
			(layer "B.CrtYd")
		)
		(fp_rect
			(start 0.4318 0.9525)
			(end -0.4318 -0.9525)
			(stroke
				(width 0)
				(type default)
			)
			(fill no)
			(layer "B.Fab")
		)
		(pad "1" smd custom
			(at 0 -0.4445 180)
			(size 0.1524 0.1524)
			(layers "B.Cu" "B.Mask" "B.Paste")
			(net "GND")
			(options
				(clearance outline)
				(anchor circle)
			)
			(primitives
				(gr_poly
					(pts
						(arc
							(start 0.3048 0.2032)
							(mid 0.275042 0.275042)
							(end 0.2032 0.3048)
						)
						(arc
							(start -0.2032 0.3048)
							(mid -0.275042 0.275042)
							(end -0.3048 0.2032)
						)
						(arc
							(start -0.3048 -0.2032)
							(mid -0.275042 -0.275042)
							(end -0.2032 -0.3048)
						)
						(arc
							(start 0.2032 -0.3048)
							(mid 0.275042 -0.275042)
							(end 0.3048 -0.2032)
						)
					)
					(width 0)
					(fill yes)
				)
			)
		)
		(pad "2" smd custom
			(at 0 0.4445 180)
			(size 0.1524 0.1524)
			(layers "B.Cu" "B.Mask" "B.Paste")
			(net "P3V3_STBY")
			(options
				(clearance outline)
				(anchor circle)
			)
			(primitives
				(gr_poly
					(pts
						(arc
							(start 0.3048 0.2032)
							(mid 0.275042 0.275042)
							(end 0.2032 0.3048)
						)
						(arc
							(start -0.2032 0.3048)
							(mid -0.275042 0.275042)
							(end -0.3048 0.2032)
						)
						(arc
							(start -0.3048 -0.2032)
							(mid -0.275042 -0.275042)
							(end -0.2032 -0.3048)
						)
						(arc
							(start 0.2032 -0.3048)
							(mid 0.275042 -0.275042)
							(end 0.3048 -0.2032)
						)
					)
					(width 0)
					(fill yes)
				)
			)
		)
	)
	(footprint ""
		(layer "B.Cu")
		(at 266.804648 -4.662678 90)
		(property "Reference" "R196"
			(at 0 0 90)
			(layer "B.SilkS")
			(hide yes)
			(effects
				(font
					(size 1.27 1.27)
				)
				(justify mirror)
			)
		)
		(property "Value" "4K7R2F-GP"
			(at -0.064008 -3.993896 90)
			(unlocked yes)
			(layer "B.Fab")
			(hide yes)
			(effects
				(font
					(size 1.016 1.016)
					(thickness 0.1524)
				)
				(justify mirror)
			)
		)
		(property "Device Type" "R402H16"
			(at -0.064008 -5.517896 90)
			(unlocked yes)
			(layer "B.Fab")
			(hide yes)
			(effects
				(font
					(size 1.016 1.016)
					(thickness 0.1524)
				)
				(justify mirror)
			)
		)
		(duplicate_pad_numbers_are_jumpers no)
		(fp_line
			(start 0.508 -0.9398)
			(end 0.508 0.9398)
			(stroke
				(width 0.1524)
				(type default)
			)
			(layer "B.SilkS")
		)
		(fp_line
			(start -0.508 -0.9398)
			(end 0.508 -0.9398)
			(stroke
				(width 0.1524)
				(type default)
			)
			(layer "B.SilkS")
		)
		(fp_rect
			(start 0.508 0.9398)
			(end -0.508 -0.9398)
			(stroke
				(width 0)
				(type default)
			)
			(fill no)
			(layer "B.CrtYd")
		)
		(fp_rect
			(start 0.508 0.9398)
			(end -0.508 -0.9398)
			(stroke
				(width 0)
				(type default)
			)
			(fill no)
			(layer "B.Fab")
		)
		(pad "1" smd custom
			(at 0 -0.4445 270)
			(size 0.1397 0.1397)
			(layers "B.Cu" "B.Mask" "B.Paste")
			(net "TEMP_1_A1")
			(options
				(clearance outline)
				(anchor circle)
			)
			(primitives
				(gr_poly
					(pts
						(arc
							(start -0.1778 0.2794)
							(mid -0.249642 0.249642)
							(end -0.2794 0.1778)
						)
						(arc
							(start -0.2794 -0.1778)
							(mid -0.249642 -0.249642)
							(end -0.1778 -0.2794)
						)
						(arc
							(start 0.1778 -0.2794)
							(mid 0.249642 -0.249642)
							(end 0.2794 -0.1778)
						)
						(arc
							(start 0.2794 0.1778)
							(mid 0.249642 0.249642)
							(end 0.1778 0.2794)
						)
					)
					(width 0)
					(fill yes)
				)
			)
		)
		(pad "2" smd custom
			(at 0 0.4445 270)
			(size 0.1397 0.1397)
			(layers "B.Cu" "B.Mask" "B.Paste")
			(net "GND")
			(options
				(clearance outline)
				(anchor circle)
			)
			(primitives
				(gr_poly
					(pts
						(arc
							(start -0.1778 0.2794)
							(mid -0.249642 0.249642)
							(end -0.2794 0.1778)
						)
						(arc
							(start -0.2794 -0.1778)
							(mid -0.249642 -0.249642)
							(end -0.1778 -0.2794)
						)
						(arc
							(start 0.1778 -0.2794)
							(mid 0.249642 -0.249642)
							(end 0.2794 -0.1778)
						)
						(arc
							(start 0.2794 0.1778)
							(mid 0.249642 0.249642)
							(end 0.1778 0.2794)
						)
					)
					(width 0)
					(fill yes)
				)
			)
		)
	)
	(footprint ""
		(layer "B.Cu")
		(at 250.707906 -39.50081 180)
		(property "Reference" "R42"
			(at 0 0 0)
			(layer "B.SilkS")
			(hide yes)
			(effects
				(font
					(size 1.27 1.27)
				)
				(justify mirror)
			)
		)
		(property "Value" "0R2J-2-GP"
			(at -0.064008 -3.993896 180)
			(unlocked yes)
			(layer "B.Fab")
			(hide yes)
			(effects
				(font
					(size 1.016 1.016)
					(thickness 0.1524)
				)
				(justify mirror)
			)
		)
		(property "Device Type" "R402H16"
			(at -0.064008 -5.517896 180)
			(unlocked yes)
			(layer "B.Fab")
			(hide yes)
			(effects
				(font
					(size 1.016 1.016)
					(thickness 0.1524)
				)
				(justify mirror)
			)
		)
		(duplicate_pad_numbers_are_jumpers no)
		(fp_line
			(start 0.508 -0.9398)
			(end 0.508 0.9398)
			(stroke
				(width 0.1524)
				(type default)
			)
			(layer "B.SilkS")
		)
		(fp_line
			(start -0.508 -0.9398)
			(end 0.508 -0.9398)
			(stroke
				(width 0.1524)
				(type default)
			)
			(layer "B.SilkS")
		)
		(fp_rect
			(start 0.508 0.9398)
			(end -0.508 -0.9398)
			(stroke
				(width 0)
				(type default)
			)
			(fill no)
			(layer "B.CrtYd")
		)
		(fp_rect
			(start 0.508 0.9398)
			(end -0.508 -0.9398)
			(stroke
				(width 0)
				(type default)
			)
			(fill no)
			(layer "B.Fab")
		)
		(pad "1" smd custom
			(at 0 -0.4445)
			(size 0.1397 0.1397)
			(layers "B.Cu" "B.Mask" "B.Paste")
			(net "VSS_573")
			(options
				(clearance outline)
				(anchor circle)
			)
			(primitives
				(gr_poly
					(pts
						(arc
							(start -0.1778 0.2794)
							(mid -0.249642 0.249642)
							(end -0.2794 0.1778)
						)
						(arc
							(start -0.2794 -0.1778)
							(mid -0.249642 -0.249642)
							(end -0.1778 -0.2794)
						)
						(arc
							(start 0.1778 -0.2794)
							(mid 0.249642 -0.249642)
							(end 0.2794 -0.1778)
						)
						(arc
							(start 0.2794 0.1778)
							(mid 0.249642 0.249642)
							(end 0.1778 0.2794)
						)
					)
					(width 0)
					(fill yes)
				)
			)
		)
		(pad "2" smd custom
			(at 0 0.4445)
			(size 0.1397 0.1397)
			(layers "B.Cu" "B.Mask" "B.Paste")
			(net "GND")
			(options
				(clearance outline)
				(anchor circle)
			)
			(primitives
				(gr_poly
					(pts
						(arc
							(start -0.1778 0.2794)
							(mid -0.249642 0.249642)
							(end -0.2794 0.1778)
						)
						(arc
							(start -0.2794 -0.1778)
							(mid -0.249642 -0.249642)
							(end -0.1778 -0.2794)
						)
						(arc
							(start 0.1778 -0.2794)
							(mid 0.249642 -0.249642)
							(end 0.2794 -0.1778)
						)
						(arc
							(start 0.2794 0.1778)
							(mid 0.249642 0.249642)
							(end 0.1778 0.2794)
						)
					)
					(width 0)
					(fill yes)
				)
			)
		)
	)
	(footprint ""
		(layer "B.Cu")
		(at 231.601518 -38.002718 90)
		(property "Reference" "TP215"
			(at 0 0 90)
			(layer "B.SilkS")
			(hide yes)
			(effects
				(font
					(size 1.27 1.27)
				)
				(justify mirror)
			)
		)
		(property "Value" "TPAD28-2-GP"
			(at 0.0127 -1.6637 90)
			(unlocked yes)
			(layer "B.Fab")
			(hide yes)
			(effects
				(font
					(size 1.016 1.016)
					(thickness 0.1524)
				)
				(justify mirror)
			)
		)
		(property "Device Type" "TPAD28"
			(at 0.0127 -3.1877 90)
			(unlocked yes)
			(layer "B.Fab")
			(hide yes)
			(effects
				(font
					(size 1.016 1.016)
					(thickness 0.1524)
				)
				(justify mirror)
			)
		)
		(duplicate_pad_numbers_are_jumpers no)
		(fp_poly
			(pts
				(arc
					(start 0 0.3556)
					(mid 0 -0.3556)
					(end 0 0.3556)
				)
			)
			(stroke
				(width 0)
				(type default)
			)
			(fill no)
			(layer "B.CrtYd")
		)
		(fp_poly
			(pts
				(arc
					(start 0 0.6096)
					(mid 0 -0.6096)
					(end 0 0.6096)
				)
			)
			(stroke
				(width 0)
				(type default)
			)
			(fill no)
			(layer "B.Fab")
		)
		(pad "1" smd circle
			(at 0 0 270)
			(size 0.7112 0.7112)
			(layers "B.Cu" "B.Mask" "B.Paste")
			(net "MDC")
		)
	)
	(footprint ""
		(layer "B.Cu")
		(at 265.213338 -3.07086 180)
		(property "Reference" "R195"
			(at 0 0 0)
			(layer "B.SilkS")
			(hide yes)
			(effects
				(font
					(size 1.27 1.27)
				)
				(justify mirror)
			)
		)
		(property "Value" "4K7R2F-GP"
			(at -0.064008 -3.993896 180)
			(unlocked yes)
			(layer "B.Fab")
			(hide yes)
			(effects
				(font
					(size 1.016 1.016)
					(thickness 0.1524)
				)
				(justify mirror)
			)
		)
		(property "Device Type" "R402H16"
			(at -0.064008 -5.517896 180)
			(unlocked yes)
			(layer "B.Fab")
			(hide yes)
			(effects
				(font
					(size 1.016 1.016)
					(thickness 0.1524)
				)
				(justify mirror)
			)
		)
		(duplicate_pad_numbers_are_jumpers no)
		(fp_line
			(start 0.508 -0.9398)
			(end 0.508 0.9398)
			(stroke
				(width 0.1524)
				(type default)
			)
			(layer "B.SilkS")
		)
		(fp_line
			(start -0.508 -0.9398)
			(end 0.508 -0.9398)
			(stroke
				(width 0.1524)
				(type default)
			)
			(layer "B.SilkS")
		)
		(fp_rect
			(start 0.508 0.9398)
			(end -0.508 -0.9398)
			(stroke
				(width 0)
				(type default)
			)
			(fill no)
			(layer "B.CrtYd")
		)
		(fp_rect
			(start 0.508 0.9398)
			(end -0.508 -0.9398)
			(stroke
				(width 0)
				(type default)
			)
			(fill no)
			(layer "B.Fab")
		)
		(pad "1" smd custom
			(at 0 -0.4445)
			(size 0.1397 0.1397)
			(layers "B.Cu" "B.Mask" "B.Paste")
			(net "TEMP_1_A0")
			(options
				(clearance outline)
				(anchor circle)
			)
			(primitives
				(gr_poly
					(pts
						(arc
							(start -0.1778 0.2794)
							(mid -0.249642 0.249642)
							(end -0.2794 0.1778)
						)
						(arc
							(start -0.2794 -0.1778)
							(mid -0.249642 -0.249642)
							(end -0.1778 -0.2794)
						)
						(arc
							(start 0.1778 -0.2794)
							(mid 0.249642 -0.249642)
							(end 0.2794 -0.1778)
						)
						(arc
							(start 0.2794 0.1778)
							(mid 0.249642 0.249642)
							(end 0.1778 0.2794)
						)
					)
					(width 0)
					(fill yes)
				)
			)
		)
		(pad "2" smd custom
			(at 0 0.4445)
			(size 0.1397 0.1397)
			(layers "B.Cu" "B.Mask" "B.Paste")
			(net "GND")
			(options
				(clearance outline)
				(anchor circle)
			)
			(primitives
				(gr_poly
					(pts
						(arc
							(start -0.1778 0.2794)
							(mid -0.249642 0.249642)
							(end -0.2794 0.1778)
						)
						(arc
							(start -0.2794 -0.1778)
							(mid -0.249642 -0.249642)
							(end -0.1778 -0.2794)
						)
						(arc
							(start 0.1778 -0.2794)
							(mid 0.249642 -0.249642)
							(end 0.2794 -0.1778)
						)
						(arc
							(start 0.2794 0.1778)
							(mid 0.249642 0.249642)
							(end 0.1778 0.2794)
						)
					)
					(width 0)
					(fill yes)
				)
			)
		)
	)
)
